(kicad_pcb
	(version 20241229)
	(generator "pcbnew")
	(generator_version "9.0")
	(general
		(thickness 1.6)
		(legacy_teardrops no)
	)
	(paper "A4")
	(title_block
		(title "environment-sensor")
		(comment 1 "footprints 74-79 of 109")
	)
	(layers
		(0 "F.Cu" signal)
		(4 "In1.Cu" signal)
		(6 "In2.Cu" signal)
		(2 "B.Cu" signal)
		(9 "F.Adhes" user "F.Adhesive")
		(11 "B.Adhes" user "B.Adhesive")
		(13 "F.Paste" user)
		(15 "B.Paste" user)
		(5 "F.SilkS" user "F.Silkscreen")
		(7 "B.SilkS" user "B.Silkscreen")
		(1 "F.Mask" user)
		(3 "B.Mask" user)
		(17 "Dwgs.User" user "User.Drawings")
		(19 "Cmts.User" user "User.Comments")
		(21 "Eco1.User" user "User.Eco1")
		(23 "Eco2.User" user "User.Eco2")
		(25 "Edge.Cuts" user)
		(27 "Margin" user)
		(31 "F.CrtYd" user "F.Courtyard")
		(29 "B.CrtYd" user "B.Courtyard")
		(35 "F.Fab" user)
		(33 "B.Fab" user)
	)
	(footprint "antmicro-footprints:C_0402_1005Metric"
		(layer "F.Cu")
		(at 188.194 125.087 90)
		(descr "Capacitor SMD 0402")
		(tags "capacitor SMD 0402")
		(property "Reference" "C12"
			(at 5.91 6.906 180)
			(layer "F.SilkS")
			(effects
				(font
					(size 0.7 0.7)
					(thickness 0.15)
				)
				(justify left bottom)
			)
		)
		(property "Value" "C_100n_0402"
			(at 0 1.4 90)
			(layer "F.Fab")
			(effects
				(font
					(size 0.7 0.7)
					(thickness 0.15)
				)
				(justify left bottom)
			)
		)
		(property "Description" "SMD Multilayer Ceramic Capacitor, 0.1 µF, 50 V, 0402 [1005 Metric], ± 10%, X5R, GRM Series"
			(at 0 0 90)
			(layer "F.Fab")
			(hide yes)
			(effects
				(font
					(size 1.27 1.27)
					(thickness 0.15)
				)
			)
		)
		(property "Author" "Antmicro"
			(at 313.281 -63.107 0)
			(layer "F.Fab")
			(hide yes)
			(effects
				(font
					(size 1 1)
					(thickness 0.15)
				)
			)
		)
		(property "Dielectric" "X5R"
			(at 313.281 -63.107 0)
			(layer "F.Fab")
			(hide yes)
			(effects
				(font
					(size 1 1)
					(thickness 0.15)
				)
			)
		)
		(property "License" "Apache-2.0"
			(at 313.281 -63.107 0)
			(layer "F.Fab")
			(hide yes)
			(effects
				(font
					(size 1 1)
					(thickness 0.15)
				)
			)
		)
		(property "MPN" "GRM155R61H104KE14D"
			(at 313.281 -63.107 0)
			(layer "F.Fab")
			(hide yes)
			(effects
				(font
					(size 1 1)
					(thickness 0.15)
				)
			)
		)
		(property "Manufacturer" "Murata"
			(at 313.281 -63.107 0)
			(layer "F.Fab")
			(hide yes)
			(effects
				(font
					(size 1 1)
					(thickness 0.15)
				)
			)
		)
		(property "Public" "False"
			(at 313.281 -63.107 0)
			(layer "F.Fab")
			(hide yes)
			(effects
				(font
					(size 1 1)
					(thickness 0.15)
				)
			)
		)
		(property "Val" "100n"
			(at 313.281 -63.107 0)
			(layer "F.Fab")
			(hide yes)
			(effects
				(font
					(size 1 1)
					(thickness 0.15)
				)
			)
		)
		(property "Voltage" "50V"
			(at 313.281 -63.107 0)
			(layer "F.Fab")
			(hide yes)
			(effects
				(font
					(size 1 1)
					(thickness 0.15)
				)
			)
		)
		(sheetfile "environment-sensor.kicad_sch")
		(attr smd)
		(fp_rect
			(start -0.925 -0.47)
			(end 0.925 0.47)
			(stroke
				(width 0.05)
				(type default)
			)
			(fill no)
			(layer "F.CrtYd")
		)
		(fp_line
			(start 0.504 -0.25)
			(end 0.504 0.248)
			(stroke
				(width 0.15)
				(type solid)
			)
			(layer "F.Fab")
		)
		(fp_line
			(start -0.494 -0.25)
			(end 0.504 -0.25)
			(stroke
				(width 0.15)
				(type solid)
			)
			(layer "F.Fab")
		)
		(fp_line
			(start 0.504 0.248)
			(end -0.494 0.248)
			(stroke
				(width 0.15)
				(type solid)
			)
			(layer "F.Fab")
		)
		(fp_line
			(start -0.494 0.248)
			(end -0.494 -0.25)
			(stroke
				(width 0.15)
				(type solid)
			)
			(layer "F.Fab")
		)
		(pad "1" smd roundrect
			(at -0.48 0 90)
			(size 0.59 0.64)
			(layers "F.Cu" "F.Mask" "F.Paste")
			(roundrect_rratio 0.25)
			(net 1 "GND")
			(pintype "passive")
		)
		(pad "2" smd roundrect
			(at 0.48 0 90)
			(size 0.59 0.64)
			(layers "F.Cu" "F.Mask" "F.Paste")
			(roundrect_rratio 0.25)
			(net 2 "+3V3")
			(pintype "passive")
		)
	)
	(footprint "antmicro-footprints:FB_0603_1608Metric"
		(layer "F.Cu")
		(at 197.759 138.115 90)
		(property "Reference" "FB3"
			(at 1.25 0.35 90)
			(layer "F.SilkS")
			(effects
				(font
					(size 0.7 0.7)
					(thickness 0.15)
				)
				(justify left bottom)
			)
		)
		(property "Value" "FB_120Z_2A_Murata-BLM18PG_0603"
			(at 0 1.5 90)
			(layer "F.Fab")
			(effects
				(font
					(size 0.7 0.7)
					(thickness 0.15)
				)
				(justify left bottom)
			)
		)
		(property "Description" "Ferrite Bead, 0603 [1608 Metric], 120 ohm, 2 A, BLM18P, 0.05 ohm, ± 25%, DC power line"
			(at 0 0 90)
			(layer "F.Fab")
			(hide yes)
			(effects
				(font
					(size 1.27 1.27)
					(thickness 0.15)
				)
			)
		)
		(property "Author" "Antmicro"
			(at 335.874 -59.644 0)
			(layer "F.Fab")
			(hide yes)
			(effects
				(font
					(size 1 1)
					(thickness 0.15)
				)
			)
		)
		(property "Current" ""
			(at 335.874 -59.644 0)
			(layer "F.Fab")
			(hide yes)
			(effects
				(font
					(size 1 1)
					(thickness 0.15)
				)
			)
		)
		(property "License" "Apache-2.0"
			(at 335.874 -59.644 0)
			(layer "F.Fab")
			(hide yes)
			(effects
				(font
					(size 1 1)
					(thickness 0.15)
				)
			)
		)
		(property "MPN" "BLM18PG121SN1D"
			(at 335.874 -59.644 0)
			(layer "F.Fab")
			(hide yes)
			(effects
				(font
					(size 1 1)
					(thickness 0.15)
				)
			)
		)
		(property "Manufacturer" "Murata"
			(at 335.874 -59.644 0)
			(layer "F.Fab")
			(hide yes)
			(effects
				(font
					(size 1 1)
					(thickness 0.15)
				)
			)
		)
		(property "Public" "False"
			(at 335.874 -59.644 0)
			(layer "F.Fab")
			(hide yes)
			(effects
				(font
					(size 1 1)
					(thickness 0.15)
				)
			)
		)
		(property "Val" "120Z/2A"
			(at 335.874 -59.644 0)
			(layer "F.Fab")
			(hide yes)
			(effects
				(font
					(size 1 1)
					(thickness 0.15)
				)
			)
		)
		(sheetfile "environment-sensor.kicad_sch")
		(attr smd)
		(fp_line
			(start -0.15 -0.4)
			(end 0.15 -0.4)
			(stroke
				(width 0.15)
				(type solid)
			)
			(layer "F.SilkS")
		)
		(fp_line
			(start -0.15 0.4)
			(end 0.15 0.4)
			(stroke
				(width 0.15)
				(type solid)
			)
			(layer "F.SilkS")
		)
		(fp_rect
			(start -1.25 -0.65)
			(end 1.25 0.65)
			(stroke
				(width 0.05)
				(type solid)
			)
			(fill no)
			(layer "F.CrtYd")
		)
		(fp_line
			(start 0.8 -0.408)
			(end -0.803 -0.408)
			(stroke
				(width 0.15)
				(type solid)
			)
			(layer "F.Fab")
		)
		(fp_line
			(start 0.8 -0.408)
			(end 0.8 0.406)
			(stroke
				(width 0.15)
				(type solid)
			)
			(layer "F.Fab")
		)
		(fp_line
			(start 0.8 0.406)
			(end -0.803 0.406)
			(stroke
				(width 0.15)
				(type solid)
			)
			(layer "F.Fab")
		)
		(fp_line
			(start -0.803 0.406)
			(end -0.803 -0.408)
			(stroke
				(width 0.15)
				(type solid)
			)
			(layer "F.Fab")
		)
		(pad "1" smd roundrect
			(at -0.7 0 90)
			(size 0.8 1)
			(layers "F.Cu" "F.Mask" "F.Paste")
			(roundrect_rratio 0.2)
			(net 30 "Net-(U3-VDDA)")
			(pintype "passive")
		)
		(pad "2" smd roundrect
			(at 0.7 0 90)
			(size 0.8 1)
			(layers "F.Cu" "F.Mask" "F.Paste")
			(roundrect_rratio 0.2)
			(net 2 "+3V3")
			(pintype "passive")
		)
	)
	(footprint "antmicro-footprints:R_0402_1005Metric"
		(layer "F.Cu")
		(at 183.75 126.25 -90)
		(descr "Resistor SMD 0402")
		(tags "resistor SMD 0402")
		(property "Reference" "R6"
			(at -10.25 -1 90)
			(layer "B.SilkS")
			(effects
				(font
					(size 0.7 0.7)
					(thickness 0.15)
				)
				(justify right bottom mirror)
			)
		)
		(property "Value" "R_0R_0402"
			(at 0 1.4 90)
			(layer "F.Fab")
			(effects
				(font
					(size 0.7 0.7)
					(thickness 0.15)
				)
				(justify right bottom)
			)
		)
		(property "Description" "SMD Chip Resistor, Jumper, 0 ohm, 100 mW, 0402 [1005 Metric], Thick Film, General Purpose"
			(at 0 0 270)
			(layer "F.Fab")
			(hide yes)
			(effects
				(font
					(size 1.27 1.27)
					(thickness 0.15)
				)
			)
		)
		(property "Author" "Antmicro"
			(at 57.5 310 0)
			(layer "F.Fab")
			(hide yes)
			(effects
				(font
					(size 1 1)
					(thickness 0.15)
				)
			)
		)
		(property "Current" "1A"
			(at 57.5 310 0)
			(layer "F.Fab")
			(hide yes)
			(effects
				(font
					(size 1 1)
					(thickness 0.15)
				)
			)
		)
		(property "License" "Apache-2.0"
			(at 57.5 310 0)
			(layer "F.Fab")
			(hide yes)
			(effects
				(font
					(size 1 1)
					(thickness 0.15)
				)
			)
		)
		(property "MPN" "ERJ2GE0R00X"
			(at 57.5 310 0)
			(layer "F.Fab")
			(hide yes)
			(effects
				(font
					(size 1 1)
					(thickness 0.15)
				)
			)
		)
		(property "Manufacturer" "Panasonic"
			(at 57.5 310 0)
			(layer "F.Fab")
			(hide yes)
			(effects
				(font
					(size 1 1)
					(thickness 0.15)
				)
			)
		)
		(property "Public" "False"
			(at 57.5 310 0)
			(layer "F.Fab")
			(hide yes)
			(effects
				(font
					(size 1 1)
					(thickness 0.15)
				)
			)
		)
		(property "Tolerance" ""
			(at 57.5 310 0)
			(layer "F.Fab")
			(hide yes)
			(effects
				(font
					(size 1 1)
					(thickness 0.15)
				)
			)
		)
		(property "Val" "0R"
			(at 57.5 310 0)
			(layer "F.Fab")
			(hide yes)
			(effects
				(font
					(size 1 1)
					(thickness 0.15)
				)
			)
		)
		(sheetfile "environment-sensor.kicad_sch")
		(attr smd)
		(fp_rect
			(start -0.925 -0.47)
			(end 0.925 0.47)
			(stroke
				(width 0.05)
				(type default)
			)
			(fill no)
			(layer "F.CrtYd")
		)
		(fp_rect
			(start -0.5 -0.25)
			(end 0.5 0.25)
			(stroke
				(width 0.15)
				(type solid)
			)
			(fill no)
			(layer "F.Fab")
		)
		(pad "1" smd roundrect
			(at -0.48 0 270)
			(size 0.59 0.64)
			(layers "F.Cu" "F.Mask" "F.Paste")
			(roundrect_rratio 0.25)
			(net 38 "Net-(U1-RTS#)")
			(pintype "passive")
		)
		(pad "2" smd roundrect
			(at 0.48 0 270)
			(size 0.59 0.64)
			(layers "F.Cu" "F.Mask" "F.Paste")
			(roundrect_rratio 0.25)
			(net 18 "SWCLK-JTCK")
			(pintype "passive")
		)
	)
	(footprint "antmicro-footprints:R_0402_1005Metric"
		(layer "F.Cu")
		(at 169.55 135)
		(descr "Resistor SMD 0402")
		(tags "resistor SMD 0402")
		(property "Reference" "R1"
			(at -2.45 0.4 0)
			(layer "F.SilkS")
			(effects
				(font
					(size 0.7 0.7)
					(thickness 0.15)
				)
				(justify left bottom)
			)
		)
		(property "Value" "R_1M_0402"
			(at -1.011843 1.772047 0)
			(layer "F.Fab")
			(effects
				(font
					(size 0.7 0.7)
					(thickness 0.15)
				)
				(justify left bottom)
			)
		)
		(property "Description" "SMD Chip Resistor, 1 Mohm, ± 1%, 62.5 mW, 0402 [1005 Metric], Thick Film, General Purpose"
			(at 0 0 0)
			(layer "F.Fab")
			(hide yes)
			(effects
				(font
					(size 1.27 1.27)
					(thickness 0.15)
				)
			)
		)
		(property "Author" "Antmicro"
			(at 0 0 0)
			(layer "F.Fab")
			(hide yes)
			(effects
				(font
					(size 1 1)
					(thickness 0.15)
				)
			)
		)
		(property "License" "Apache-2.0"
			(at 0 0 0)
			(layer "F.Fab")
			(hide yes)
			(effects
				(font
					(size 1 1)
					(thickness 0.15)
				)
			)
		)
		(property "MPN" "CR0402-FX-1004GLF"
			(at 0 0 0)
			(layer "F.Fab")
			(hide yes)
			(effects
				(font
					(size 1 1)
					(thickness 0.15)
				)
			)
		)
		(property "Manufacturer" "Bourns"
			(at 0 0 0)
			(layer "F.Fab")
			(hide yes)
			(effects
				(font
					(size 1 1)
					(thickness 0.15)
				)
			)
		)
		(property "Public" "False"
			(at 0 0 0)
			(layer "F.Fab")
			(hide yes)
			(effects
				(font
					(size 1 1)
					(thickness 0.15)
				)
			)
		)
		(property "Tolerance" "1%"
			(at 0 0 0)
			(layer "F.Fab")
			(hide yes)
			(effects
				(font
					(size 1 1)
					(thickness 0.15)
				)
			)
		)
		(property "Val" "1M"
			(at 0 0 0)
			(layer "F.Fab")
			(hide yes)
			(effects
				(font
					(size 1 1)
					(thickness 0.15)
				)
			)
		)
		(sheetfile "environment-sensor.kicad_sch")
		(attr smd exclude_from_pos_files exclude_from_bom dnp)
		(fp_rect
			(start -0.925 -0.47)
			(end 0.925 0.47)
			(stroke
				(width 0.05)
				(type default)
			)
			(fill no)
			(layer "F.CrtYd")
		)
		(fp_rect
			(start -0.5 -0.25)
			(end 0.5 0.25)
			(stroke
				(width 0.15)
				(type solid)
			)
			(fill no)
			(layer "F.Fab")
		)
		(pad "1" smd roundrect
			(at -0.48 0)
			(size 0.59 0.64)
			(layers "F.Cu" "F.Mask" "F.Paste")
			(roundrect_rratio 0.25)
			(net 3 "GNDREF")
			(pintype "passive")
		)
		(pad "2" smd roundrect
			(at 0.48 0)
			(size 0.59 0.64)
			(layers "F.Cu" "F.Mask" "F.Paste")
			(roundrect_rratio 0.25)
			(net 1 "GND")
			(pintype "passive")
		)
	)
	(footprint "antmicro-footprints:C_0402_1005Metric"
		(layer "F.Cu")
		(at 175.209 123.684 90)
		(descr "Capacitor SMD 0402")
		(tags "capacitor SMD 0402")
		(property "Reference" "C3"
			(at -2.445 0.407 90)
			(layer "F.SilkS")
			(effects
				(font
					(size 0.7 0.7)
					(thickness 0.15)
				)
				(justify left bottom)
			)
		)
		(property "Value" "C_100n_0402"
			(at 0 1.4 90)
			(layer "F.Fab")
			(effects
				(font
					(size 0.7 0.7)
					(thickness 0.15)
				)
				(justify left bottom)
			)
		)
		(property "Description" "SMD Multilayer Ceramic Capacitor, 0.1 µF, 50 V, 0402 [1005 Metric], ± 10%, X5R, GRM Series"
			(at 0 0 90)
			(layer "F.Fab")
			(hide yes)
			(effects
				(font
					(size 1.27 1.27)
					(thickness 0.15)
				)
			)
		)
		(property "Author" "Antmicro"
			(at 298.893 -51.525 0)
			(layer "F.Fab")
			(hide yes)
			(effects
				(font
					(size 1 1)
					(thickness 0.15)
				)
			)
		)
		(property "Dielectric" "X5R"
			(at 298.893 -51.525 0)
			(layer "F.Fab")
			(hide yes)
			(effects
				(font
					(size 1 1)
					(thickness 0.15)
				)
			)
		)
		(property "License" "Apache-2.0"
			(at 298.893 -51.525 0)
			(layer "F.Fab")
			(hide yes)
			(effects
				(font
					(size 1 1)
					(thickness 0.15)
				)
			)
		)
		(property "MPN" "GRM155R61H104KE14D"
			(at 298.893 -51.525 0)
			(layer "F.Fab")
			(hide yes)
			(effects
				(font
					(size 1 1)
					(thickness 0.15)
				)
			)
		)
		(property "Manufacturer" "Murata"
			(at 298.893 -51.525 0)
			(layer "F.Fab")
			(hide yes)
			(effects
				(font
					(size 1 1)
					(thickness 0.15)
				)
			)
		)
		(property "Public" "False"
			(at 298.893 -51.525 0)
			(layer "F.Fab")
			(hide yes)
			(effects
				(font
					(size 1 1)
					(thickness 0.15)
				)
			)
		)
		(property "Val" "100n"
			(at 298.893 -51.525 0)
			(layer "F.Fab")
			(hide yes)
			(effects
				(font
					(size 1 1)
					(thickness 0.15)
				)
			)
		)
		(property "Voltage" "50V"
			(at 298.893 -51.525 0)
			(layer "F.Fab")
			(hide yes)
			(effects
				(font
					(size 1 1)
					(thickness 0.15)
				)
			)
		)
		(sheetfile "environment-sensor.kicad_sch")
		(attr smd)
		(fp_rect
			(start -0.925 -0.47)
			(end 0.925 0.47)
			(stroke
				(width 0.05)
				(type default)
			)
			(fill no)
			(layer "F.CrtYd")
		)
		(fp_line
			(start 0.504 -0.25)
			(end 0.504 0.248)
			(stroke
				(width 0.15)
				(type solid)
			)
			(layer "F.Fab")
		)
		(fp_line
			(start -0.494 -0.25)
			(end 0.504 -0.25)
			(stroke
				(width 0.15)
				(type solid)
			)
			(layer "F.Fab")
		)
		(fp_line
			(start 0.504 0.248)
			(end -0.494 0.248)
			(stroke
				(width 0.15)
				(type solid)
			)
			(layer "F.Fab")
		)
		(fp_line
			(start -0.494 0.248)
			(end -0.494 -0.25)
			(stroke
				(width 0.15)
				(type solid)
			)
			(layer "F.Fab")
		)
		(pad "1" smd roundrect
			(at -0.48 0 90)
			(size 0.59 0.64)
			(layers "F.Cu" "F.Mask" "F.Paste")
			(roundrect_rratio 0.25)
			(net 1 "GND")
			(pintype "passive")
		)
		(pad "2" smd roundrect
			(at 0.48 0 90)
			(size 0.59 0.64)
			(layers "F.Cu" "F.Mask" "F.Paste")
			(roundrect_rratio 0.25)
			(net 26 "+5V")
			(pintype "passive")
		)
	)
	(footprint "antmicro-footprints:FB_0603_1608Metric"
		(layer "F.Cu")
		(at 169.25 133.6)
		(property "Reference" "FB1"
			(at -3.4 0.4 0)
			(layer "F.SilkS")
			(effects
				(font
					(size 0.7 0.7)
					(thickness 0.15)
				)
				(justify left bottom)
			)
		)
		(property "Value" "FB_120Z_2A_Murata-BLM18PG_0603"
			(at 0 1.5 0)
			(layer "F.Fab")
			(effects
				(font
					(size 0.7 0.7)
					(thickness 0.15)
				)
				(justify left bottom)
			)
		)
		(property "Description" "Ferrite Bead, 0603 [1608 Metric], 120 ohm, 2 A, BLM18P, 0.05 ohm, ± 25%, DC power line"
			(at 0 0 0)
			(layer "F.Fab")
			(hide yes)
			(effects
				(font
					(size 1.27 1.27)
					(thickness 0.15)
				)
			)
		)
		(property "Author" "Antmicro"
			(at 0 0 0)
			(layer "F.Fab")
			(hide yes)
			(effects
				(font
					(size 1 1)
					(thickness 0.15)
				)
			)
		)
		(property "Current" ""
			(at 0 0 0)
			(layer "F.Fab")
			(hide yes)
			(effects
				(font
					(size 1 1)
					(thickness 0.15)
				)
			)
		)
		(property "License" "Apache-2.0"
			(at 0 0 0)
			(layer "F.Fab")
			(hide yes)
			(effects
				(font
					(size 1 1)
					(thickness 0.15)
				)
			)
		)
		(property "MPN" "BLM18PG121SN1D"
			(at 0 0 0)
			(layer "F.Fab")
			(hide yes)
			(effects
				(font
					(size 1 1)
					(thickness 0.15)
				)
			)
		)
		(property "Manufacturer" "Murata"
			(at 0 0 0)
			(layer "F.Fab")
			(hide yes)
			(effects
				(font
					(size 1 1)
					(thickness 0.15)
				)
			)
		)
		(property "Public" "False"
			(at 0 0 0)
			(layer "F.Fab")
			(hide yes)
			(effects
				(font
					(size 1 1)
					(thickness 0.15)
				)
			)
		)
		(property "Val" "120Z/2A"
			(at 0 0 0)
			(layer "F.Fab")
			(hide yes)
			(effects
				(font
					(size 1 1)
					(thickness 0.15)
				)
			)
		)
		(sheetfile "environment-sensor.kicad_sch")
		(attr smd)
		(fp_line
			(start -0.15 -0.4)
			(end 0.15 -0.4)
			(stroke
				(width 0.15)
				(type solid)
			)
			(layer "F.SilkS")
		)
		(fp_line
			(start -0.15 0.4)
			(end 0.15 0.4)
			(stroke
				(width 0.15)
				(type solid)
			)
			(layer "F.SilkS")
		)
		(fp_rect
			(start -1.25 -0.65)
			(end 1.25 0.65)
			(stroke
				(width 0.05)
				(type solid)
			)
			(fill no)
			(layer "F.CrtYd")
		)
		(fp_line
			(start -0.803 0.406)
			(end -0.803 -0.408)
			(stroke
				(width 0.15)
				(type solid)
			)
			(layer "F.Fab")
		)
		(fp_line
			(start 0.8 -0.408)
			(end -0.803 -0.408)
			(stroke
				(width 0.15)
				(type solid)
			)
			(layer "F.Fab")
		)
		(fp_line
			(start 0.8 -0.408)
			(end 0.8 0.406)
			(stroke
				(width 0.15)
				(type solid)
			)
			(layer "F.Fab")
		)
		(fp_line
			(start 0.8 0.406)
			(end -0.803 0.406)
			(stroke
				(width 0.15)
				(type solid)
			)
			(layer "F.Fab")
		)
		(pad "1" smd roundrect
			(at -0.7 0)
			(size 0.8 1)
			(layers "F.Cu" "F.Mask" "F.Paste")
			(roundrect_rratio 0.2)
			(net 3 "GNDREF")
			(pintype "passive")
		)
		(pad "2" smd roundrect
			(at 0.7 0)
			(size 0.8 1)
			(layers "F.Cu" "F.Mask" "F.Paste")
			(roundrect_rratio 0.2)
			(net 1 "GND")
			(pintype "passive")
		)
	)
)
